# S9S_MB_2U (Grand Teton) — schematic netlist excerpt (pin names and nets, part order shuffled) for the footprints in the layout excerpt that follows; sources: Cadence DE-HDL packaged netlist, KiCad conversion of 03242023_DA0F0TMBIJ0_F0T_Motherboard_J_brd_V01_OCP.brd

R2403  Q_RES  0 5% CHIP  pkg 0402LF  page 278 : A = SMB_VR_3V3AUX_SDA_R2 ; B = SMB_DIO_PVCCD_HV_CPU0
C1547  Q_CAP_DIFFBUS  DIFF BUS_0.22UF 6.3V 20% X6S  pkg C0201  page 177 : \1\ = P5E_CPU1_PE3_TX_C_DP<0> ; \2\ = P5E_CPU1_PE3_TX_DP<0>
C875  Q_CAP_DIFFBUS  DIFF BUS_0.22UF 6.3V 20% X6S  pkg C0201  page 174 : \1\ = P5E_CPU0_PE3_TX_C_DP<13> ; \2\ = P5E_CPU0_PE3_TX_DP<13>

(kicad_pcb
	(version 20260206)
	(generator "pcbnew")
	(generator_version "10.0")
	(general
		(thickness 1.6)
		(legacy_teardrops no)
	)
	(paper "A4")
	(title_block
		(title "03242023_DA0F0TMBIJ0_F0T_Motherboard_J_brd_V01_OCP.brd")
		(comment 1 "Grand Teton / footprints 3147-3149 of 6105")
	)
	(layers
		(0 "F.Cu" signal "TOP")
		(4 "In1.Cu" signal "GND")
		(6 "In2.Cu" signal "IN1")
		(8 "In3.Cu" signal "GND1")
		(10 "In4.Cu" signal "IN2")
		(12 "In5.Cu" signal "GND2")
		(14 "In6.Cu" signal "IN3")
		(16 "In7.Cu" signal "GND3")
		(18 "In8.Cu" signal "VCC")
		(20 "In9.Cu" signal "VCC1")
		(22 "In10.Cu" signal "GND4")
		(24 "In11.Cu" signal "IN4")
		(26 "In12.Cu" signal "GND5")
		(28 "In13.Cu" signal "IN5")
		(30 "In14.Cu" signal "GND6")
		(32 "In15.Cu" signal "IN6")
		(34 "In16.Cu" signal "GND7")
		(2 "B.Cu" signal "BOTTOM")
		(9 "F.Adhes" user "F.Adhesive")
		(11 "B.Adhes" user "B.Adhesive")
		(13 "F.Paste" user "Package Geometry/Pastemask Top")
		(15 "B.Paste" user "Package Geometry/Pastemask Bottom")
		(5 "F.SilkS" user "Ref Des/Silkscreen Top")
		(7 "B.SilkS" user "Ref Des/Silkscreen Bottom")
		(1 "F.Mask" user "Board Geometry/Soldermask Top")
		(3 "B.Mask" user "Board Geometry/Soldermask Bottom")
		(17 "Dwgs.User" user "User.Drawings")
		(19 "Cmts.User" user "User.Comments")
		(21 "Eco1.User" user "User.Eco1")
		(23 "Eco2.User" user "User.Eco2")
		(25 "Edge.Cuts" user "Board Geometry/Outline")
		(27 "Margin" user)
		(31 "F.CrtYd" user "Package Geometry/Place Bound Top")
		(29 "B.CrtYd" user "Package Geometry/Place Bound Bottom")
		(35 "F.Fab" user "Ref Des/Assembly Top")
		(33 "B.Fab" user "Ref Des/Assembly Bottom")
	)
	(footprint ""
		(layer "F.Cu")
		(at 434.080158 -118.568216 90)
		(property "Reference" "R2403"
			(at 0 0 90)
			(layer "F.SilkS")
			(hide yes)
			(effects
				(font
					(size 1.27 1.27)
				)
			)
		)
		(property "Value" ""
			(at 0 0 90)
			(layer "F.Fab")
			(effects
				(font
					(size 1.27 1.27)
				)
			)
		)
		(duplicate_pad_numbers_are_jumpers no)
		(fp_line
			(start 0.7874 -0.4064)
			(end 0.7874 0.4064)
			(stroke
				(width 0.1524)
				(type default)
			)
			(layer "F.SilkS")
		)
		(fp_line
			(start -0.7874 -0.4064)
			(end 0.7874 -0.4064)
			(stroke
				(width 0.1524)
				(type default)
			)
			(layer "F.SilkS")
		)
		(fp_line
			(start 0.7874 0.4064)
			(end -0.7874 0.4064)
			(stroke
				(width 0.1524)
				(type default)
			)
			(layer "F.SilkS")
		)
		(fp_line
			(start -0.7874 0.4064)
			(end -0.7874 -0.4064)
			(stroke
				(width 0.1524)
				(type default)
			)
			(layer "F.SilkS")
		)
		(fp_line
			(start -0.12065 -0.305054)
			(end -0.12065 -0.2794)
			(stroke
				(width 0.1)
				(type default)
			)
			(layer "F.Fab")
		)
		(fp_line
			(start -0.67945 -0.305054)
			(end -0.12065 -0.305054)
			(stroke
				(width 0.1)
				(type default)
			)
			(layer "F.Fab")
		)
		(fp_line
			(start 0.67945 -0.3048)
			(end 0.67945 0.3048)
			(stroke
				(width 0.1)
				(type default)
			)
			(layer "F.Fab")
		)
		(fp_line
			(start 0.12065 -0.3048)
			(end 0.67945 -0.3048)
			(stroke
				(width 0.1)
				(type default)
			)
			(layer "F.Fab")
		)
		(fp_line
			(start 0.12065 -0.2794)
			(end 0.12065 -0.3048)
			(stroke
				(width 0.1)
				(type default)
			)
			(layer "F.Fab")
		)
		(fp_line
			(start -0.12065 -0.2794)
			(end 0.12065 -0.2794)
			(stroke
				(width 0.1)
				(type default)
			)
			(layer "F.Fab")
		)
		(fp_line
			(start 0.120396 0.2794)
			(end -0.12065 0.2794)
			(stroke
				(width 0.1)
				(type default)
			)
			(layer "F.Fab")
		)
		(fp_line
			(start -0.12065 0.2794)
			(end -0.12065 0.3048)
			(stroke
				(width 0.1)
				(type default)
			)
			(layer "F.Fab")
		)
		(fp_line
			(start 0.67945 0.3048)
			(end 0.120396 0.3048)
			(stroke
				(width 0.1)
				(type default)
			)
			(layer "F.Fab")
		)
		(fp_line
			(start 0.120396 0.3048)
			(end 0.120396 0.2794)
			(stroke
				(width 0.1)
				(type default)
			)
			(layer "F.Fab")
		)
		(fp_line
			(start -0.12065 0.3048)
			(end -0.67945 0.3048)
			(stroke
				(width 0.1)
				(type default)
			)
			(layer "F.Fab")
		)
		(fp_line
			(start -0.67945 0.3048)
			(end -0.67945 -0.305054)
			(stroke
				(width 0.1)
				(type default)
			)
			(layer "F.Fab")
		)
		(pad "1" smd circle
			(at -0.40005 0 90)
			(size 0 0)
			(layers "F.Cu" "F.Mask" "F.Paste")
			(net "SMB_VR_3V3AUX_SDA_R2")
		)
		(pad "2" smd circle
			(at 0.40005 0 90)
			(size 0 0)
			(layers "F.Cu" "F.Mask" "F.Paste")
			(net "SMB_DIO_PVCCD_HV_CPU0")
		)
	)
	(footprint ""
		(layer "F.Cu")
		(at 379.78461 -408.517344 -90)
		(property "Reference" "C875"
			(at 0 0 270)
			(layer "F.SilkS")
			(hide yes)
			(effects
				(font
					(size 1.27 1.27)
				)
			)
		)
		(property "Value" ""
			(at 0 0 270)
			(layer "F.Fab")
			(effects
				(font
					(size 1.27 1.27)
				)
			)
		)
		(duplicate_pad_numbers_are_jumpers no)
		(fp_line
			(start -0.299974 0.150114)
			(end -0.299974 -0.150114)
			(stroke
				(width 0.1)
				(type default)
			)
			(layer "F.Fab")
		)
		(fp_line
			(start 0.299974 0.150114)
			(end -0.299974 0.150114)
			(stroke
				(width 0.1)
				(type default)
			)
			(layer "F.Fab")
		)
		(fp_line
			(start -0.299974 -0.150114)
			(end 0.299974 -0.150114)
			(stroke
				(width 0.1)
				(type default)
			)
			(layer "F.Fab")
		)
		(fp_line
			(start 0.299974 -0.150114)
			(end 0.299974 0.150114)
			(stroke
				(width 0.1)
				(type default)
			)
			(layer "F.Fab")
		)
		(pad "1" smd rect
			(at -0.2667 0 270)
			(size 0.3048 0.381)
			(layers "F.Cu" "F.Mask" "F.Paste")
			(net "P5E_CPU0_PE3_TX_C_DP<13>")
		)
		(pad "2" smd rect
			(at 0.2667 0 270)
			(size 0.3048 0.381)
			(layers "F.Cu" "F.Mask" "F.Paste")
			(net "P5E_CPU0_PE3_TX_DP<13>")
		)
	)
	(footprint ""
		(layer "F.Cu")
		(at 167.424354 -408.517344 -90)
		(property "Reference" "C1547"
			(at 0 0 270)
			(layer "F.SilkS")
			(hide yes)
			(effects
				(font
					(size 1.27 1.27)
				)
			)
		)
		(property "Value" ""
			(at 0 0 270)
			(layer "F.Fab")
			(effects
				(font
					(size 1.27 1.27)
				)
			)
		)
		(duplicate_pad_numbers_are_jumpers no)
		(fp_line
			(start -0.299974 0.150114)
			(end -0.299974 -0.150114)
			(stroke
				(width 0.1)
				(type default)
			)
			(layer "F.Fab")
		)
		(fp_line
			(start 0.299974 0.150114)
			(end -0.299974 0.150114)
			(stroke
				(width 0.1)
				(type default)
			)
			(layer "F.Fab")
		)
		(fp_line
			(start -0.299974 -0.150114)
			(end 0.299974 -0.150114)
			(stroke
				(width 0.1)
				(type default)
			)
			(layer "F.Fab")
		)
		(fp_line
			(start 0.299974 -0.150114)
			(end 0.299974 0.150114)
			(stroke
				(width 0.1)
				(type default)
			)
			(layer "F.Fab")
		)
		(pad "1" smd rect
			(at -0.2667 0 270)
			(size 0.3048 0.381)
			(layers "F.Cu" "F.Mask" "F.Paste")
			(net "P5E_CPU1_PE3_TX_C_DP<0>")
		)
		(pad "2" smd rect
			(at 0.2667 0 270)
			(size 0.3048 0.381)
			(layers "F.Cu" "F.Mask" "F.Paste")
			(net "P5E_CPU1_PE3_TX_DP<0>")
		)
	)
)
